(kicad_pcb
	(version 20260206)
	(generator "pcbnew")
	(generator_version "10.0")
	(general
		(thickness 1.6)
		(legacy_teardrops no)
	)
	(paper "A4")
	(title_block
		(title "v1-chassis-manager — T6M_CM_d_v01_1031_1645.brd")
		(comment 1 "Open CloudServer (Microsoft) / footprints 1613-1622 of 2512")
	)
	(layers
		(0 "F.Cu" signal "TOP")
		(4 "In1.Cu" signal "GND1")
		(6 "In2.Cu" signal "IN1")
		(8 "In3.Cu" signal "VCC1")
		(10 "In4.Cu" signal "VCC2")
		(12 "In5.Cu" signal "GND2")
		(14 "In6.Cu" signal "IN2")
		(16 "In7.Cu" signal "IN3")
		(18 "In8.Cu" signal "GND3")
		(2 "B.Cu" signal "BOTTOM")
		(9 "F.Adhes" user "F.Adhesive")
		(11 "B.Adhes" user "B.Adhesive")
		(13 "F.Paste" user "Package Geometry/Pastemask Top")
		(15 "B.Paste" user "Package Geometry/Pastemask Bottom")
		(5 "F.SilkS" user "Ref Des/Silkscreen Top")
		(7 "B.SilkS" user "Ref Des/Silkscreen Bottom")
		(1 "F.Mask" user "Board Geometry/Soldermask Top")
		(3 "B.Mask" user "Board Geometry/Soldermask Bottom")
		(17 "Dwgs.User" user "User.Drawings")
		(19 "Cmts.User" user "User.Comments")
		(21 "Eco1.User" user "User.Eco1")
		(23 "Eco2.User" user "User.Eco2")
		(25 "Edge.Cuts" user "Board Geometry/Outline")
		(27 "Margin" user)
		(31 "F.CrtYd" user "Package Geometry/Place Bound Top")
		(29 "B.CrtYd" user "Package Geometry/Place Bound Bottom")
		(35 "F.Fab" user "Ref Des/Assembly Top")
		(33 "B.Fab" user "Ref Des/Assembly Bottom")
	)
	(footprint ""
		(layer "B.Cu")
		(at 137.970006 -36.42741)
		(property "Reference" "R1182"
			(at -3.527806 18.57248 0)
			(unlocked yes)
			(layer "B.SilkS")
			(effects
				(font
					(size 0.7874 0.5842)
					(thickness 0.1524)
				)
				(justify left mirror)
			)
		)
		(property "Value" ""
			(at 0 0 0)
			(layer "B.Fab")
			(effects
				(font
					(size 1.27 1.27)
				)
				(justify mirror)
			)
		)
		(duplicate_pad_numbers_are_jumpers no)
		(fp_line
			(start -0.7874 -0.4064)
			(end -0.7874 0.4064)
			(stroke
				(width 0.1524)
				(type default)
			)
			(layer "B.SilkS")
		)
		(fp_line
			(start -0.7874 0.4064)
			(end 0.7874 0.4064)
			(stroke
				(width 0.1524)
				(type default)
			)
			(layer "B.SilkS")
		)
		(fp_line
			(start 0.7874 -0.4064)
			(end -0.7874 -0.4064)
			(stroke
				(width 0.1524)
				(type default)
			)
			(layer "B.SilkS")
		)
		(fp_line
			(start 0.7874 0.4064)
			(end 0.7874 -0.4064)
			(stroke
				(width 0.1524)
				(type default)
			)
			(layer "B.SilkS")
		)
		(fp_poly
			(pts
				(xy 0.508 0.2794) (xy 0.508 0.2286) (xy 0.635 0.2286) (xy 0.635 -0.254) (xy 0.5334 -0.254) (xy 0.5334 -0.2794)
				(xy -0.5334 -0.2794) (xy -0.5334 -0.254) (xy -0.635 -0.254) (xy -0.635 0.254) (xy -0.5334 0.254)
				(xy -0.5334 0.2794)
			)
			(stroke
				(width 0)
				(type default)
			)
			(fill no)
			(layer "B.CrtYd")
		)
		(pad "1" smd rect
			(at -0.40005 0 180)
			(size 0.4572 0.508)
			(layers "B.Cu" "B.Mask" "B.Paste")
			(net "SIO_CPLD_RSV1_R")
		)
		(pad "2" smd rect
			(at 0.40005 0 180)
			(size 0.4572 0.508)
			(layers "B.Cu" "B.Mask" "B.Paste")
			(net "GND")
		)
	)
	(footprint ""
		(layer "B.Cu")
		(at 75.04176 -188.126624 90)
		(property "Reference" "R908"
			(at 4.318254 -0.374396 270)
			(unlocked yes)
			(layer "B.SilkS")
			(effects
				(font
					(size 0.7874 0.5842)
					(thickness 0.1524)
				)
				(justify left mirror)
			)
		)
		(property "Value" ""
			(at 0 0 90)
			(layer "B.Fab")
			(effects
				(font
					(size 1.27 1.27)
				)
				(justify mirror)
			)
		)
		(duplicate_pad_numbers_are_jumpers no)
		(fp_line
			(start 0.7874 -0.4064)
			(end -0.7874 -0.4064)
			(stroke
				(width 0.1524)
				(type default)
			)
			(layer "B.SilkS")
		)
		(fp_line
			(start -0.7874 -0.4064)
			(end -0.7874 0.4064)
			(stroke
				(width 0.1524)
				(type default)
			)
			(layer "B.SilkS")
		)
		(fp_line
			(start 0.7874 0.4064)
			(end 0.7874 -0.4064)
			(stroke
				(width 0.1524)
				(type default)
			)
			(layer "B.SilkS")
		)
		(fp_line
			(start -0.7874 0.4064)
			(end 0.7874 0.4064)
			(stroke
				(width 0.1524)
				(type default)
			)
			(layer "B.SilkS")
		)
		(fp_poly
			(pts
				(xy 0.508 0.2794) (xy 0.508 0.2286) (xy 0.635 0.2286) (xy 0.635 -0.254) (xy 0.5334 -0.254) (xy 0.5334 -0.2794)
				(xy -0.5334 -0.2794) (xy -0.5334 -0.254) (xy -0.635 -0.254) (xy -0.635 0.254) (xy -0.5334 0.254)
				(xy -0.5334 0.2794)
			)
			(stroke
				(width 0)
				(type default)
			)
			(fill no)
			(layer "B.CrtYd")
		)
		(pad "1" smd rect
			(at -0.40005 0 270)
			(size 0.4572 0.508)
			(layers "B.Cu" "B.Mask" "B.Paste")
			(net "UART_T3_NODE1_RXD")
		)
		(pad "2" smd rect
			(at 0.40005 0 270)
			(size 0.4572 0.508)
			(layers "B.Cu" "B.Mask" "B.Paste")
			(net "UART_T3_NODE1_RXD_R")
		)
	)
	(footprint ""
		(layer "B.Cu")
		(at 163.128452 -98.37039 180)
		(property "Reference" "C382"
			(at -4.541012 0.480314 0)
			(unlocked yes)
			(layer "B.SilkS")
			(effects
				(font
					(size 0.7874 0.5842)
					(thickness 0.1524)
				)
				(justify left mirror)
			)
		)
		(property "Value" ""
			(at 0 0 0)
			(layer "B.Fab")
			(effects
				(font
					(size 1.27 1.27)
				)
				(justify mirror)
			)
		)
		(duplicate_pad_numbers_are_jumpers no)
		(fp_line
			(start 0.7874 0.4064)
			(end 0.7874 -0.4064)
			(stroke
				(width 0.1524)
				(type default)
			)
			(layer "B.SilkS")
		)
		(fp_line
			(start 0.7874 -0.4064)
			(end -0.7874 -0.4064)
			(stroke
				(width 0.1524)
				(type default)
			)
			(layer "B.SilkS")
		)
		(fp_line
			(start 0 0.381)
			(end 0 -0.381)
			(stroke
				(width 0.1524)
				(type default)
			)
			(layer "B.SilkS")
		)
		(fp_line
			(start -0.7874 0.4064)
			(end 0.7874 0.4064)
			(stroke
				(width 0.1524)
				(type default)
			)
			(layer "B.SilkS")
		)
		(fp_line
			(start -0.7874 -0.4064)
			(end -0.7874 0.4064)
			(stroke
				(width 0.1524)
				(type default)
			)
			(layer "B.SilkS")
		)
		(fp_poly
			(pts
				(xy 0.5334 0.254) (xy 0.635 0.254) (xy 0.635 0.2286) (xy 0.635 -0.254) (xy 0.5334 -0.254) (xy 0.5334 -0.2794)
				(xy -0.5334 -0.2794) (xy -0.5334 -0.254) (xy -0.635 -0.254) (xy -0.635 0.254) (xy -0.5334 0.254)
				(xy -0.5334 0.2794) (xy 0.508 0.2794) (xy 0.5334 0.2794)
			)
			(stroke
				(width 0)
				(type default)
			)
			(fill no)
			(layer "B.CrtYd")
		)
		(pad "1" smd rect
			(at -0.40005 0)
			(size 0.4572 0.508)
			(layers "B.Cu" "B.Mask" "B.Paste")
			(net "GND")
		)
		(pad "2" smd rect
			(at 0.40005 0)
			(size 0.4572 0.508)
			(layers "B.Cu" "B.Mask" "B.Paste")
			(net "P3V3_NODE1")
		)
	)
	(footprint ""
		(layer "B.Cu")
		(at 136.483852 -116.871242 180)
		(property "Reference" "C3"
			(at -0.739902 0.926592 0)
			(unlocked yes)
			(layer "B.SilkS")
			(effects
				(font
					(size 0.7874 0.5842)
					(thickness 0.1524)
				)
				(justify left mirror)
			)
		)
		(property "Value" ""
			(at 0 0 0)
			(layer "B.Fab")
			(effects
				(font
					(size 1.27 1.27)
				)
				(justify mirror)
			)
		)
		(duplicate_pad_numbers_are_jumpers no)
		(fp_line
			(start 0.7874 0.4064)
			(end 0.7874 -0.4064)
			(stroke
				(width 0.1524)
				(type default)
			)
			(layer "B.SilkS")
		)
		(fp_line
			(start 0.7874 -0.4064)
			(end -0.7874 -0.4064)
			(stroke
				(width 0.1524)
				(type default)
			)
			(layer "B.SilkS")
		)
		(fp_line
			(start 0 0.381)
			(end 0 -0.381)
			(stroke
				(width 0.1524)
				(type default)
			)
			(layer "B.SilkS")
		)
		(fp_line
			(start -0.7874 0.4064)
			(end 0.7874 0.4064)
			(stroke
				(width 0.1524)
				(type default)
			)
			(layer "B.SilkS")
		)
		(fp_line
			(start -0.7874 -0.4064)
			(end -0.7874 0.4064)
			(stroke
				(width 0.1524)
				(type default)
			)
			(layer "B.SilkS")
		)
		(fp_poly
			(pts
				(xy 0.5334 0.254) (xy 0.635 0.254) (xy 0.635 0.2286) (xy 0.635 -0.254) (xy 0.5334 -0.254) (xy 0.5334 -0.2794)
				(xy -0.5334 -0.2794) (xy -0.5334 -0.254) (xy -0.635 -0.254) (xy -0.635 0.254) (xy -0.5334 0.254)
				(xy -0.5334 0.2794) (xy 0.508 0.2794) (xy 0.5334 0.2794)
			)
			(stroke
				(width 0)
				(type default)
			)
			(fill no)
			(layer "B.CrtYd")
		)
		(pad "1" smd rect
			(at -0.40005 0)
			(size 0.4572 0.508)
			(layers "B.Cu" "B.Mask" "B.Paste")
			(net "P3V3_CLK_NODE1")
		)
		(pad "2" smd rect
			(at 0.40005 0)
			(size 0.4572 0.508)
			(layers "B.Cu" "B.Mask" "B.Paste")
			(net "GND")
		)
	)
	(footprint ""
		(layer "B.Cu")
		(at 113.14176 -185.205624 -90)
		(property "Reference" "C724"
			(at -3.957828 -0.52832 270)
			(unlocked yes)
			(layer "B.SilkS")
			(effects
				(font
					(size 0.7874 0.5842)
					(thickness 0.1524)
				)
				(justify left mirror)
			)
		)
		(property "Value" ""
			(at 0 0 90)
			(layer "B.Fab")
			(effects
				(font
					(size 1.27 1.27)
				)
				(justify mirror)
			)
		)
		(duplicate_pad_numbers_are_jumpers no)
		(fp_line
			(start -0.7874 0.4064)
			(end 0.7874 0.4064)
			(stroke
				(width 0.1524)
				(type default)
			)
			(layer "B.SilkS")
		)
		(fp_line
			(start 0.7874 0.4064)
			(end 0.7874 -0.4064)
			(stroke
				(width 0.1524)
				(type default)
			)
			(layer "B.SilkS")
		)
		(fp_line
			(start 0 0.381)
			(end 0 -0.381)
			(stroke
				(width 0.1524)
				(type default)
			)
			(layer "B.SilkS")
		)
		(fp_line
			(start -0.7874 -0.4064)
			(end -0.7874 0.4064)
			(stroke
				(width 0.1524)
				(type default)
			)
			(layer "B.SilkS")
		)
		(fp_line
			(start 0.7874 -0.4064)
			(end -0.7874 -0.4064)
			(stroke
				(width 0.1524)
				(type default)
			)
			(layer "B.SilkS")
		)
		(fp_poly
			(pts
				(xy 0.5334 0.254) (xy 0.635 0.254) (xy 0.635 0.2286) (xy 0.635 -0.254) (xy 0.5334 -0.254) (xy 0.5334 -0.2794)
				(xy -0.5334 -0.2794) (xy -0.5334 -0.254) (xy -0.635 -0.254) (xy -0.635 0.254) (xy -0.5334 0.254)
				(xy -0.5334 0.2794) (xy 0.508 0.2794) (xy 0.5334 0.2794)
			)
			(stroke
				(width 0)
				(type default)
			)
			(fill no)
			(layer "B.CrtYd")
		)
		(pad "1" smd rect
			(at -0.40005 0 90)
			(size 0.4572 0.508)
			(layers "B.Cu" "B.Mask" "B.Paste")
			(net "UART_T7_NODE2_RXD")
		)
		(pad "2" smd rect
			(at 0.40005 0 90)
			(size 0.4572 0.508)
			(layers "B.Cu" "B.Mask" "B.Paste")
			(net "GND")
		)
	)
	(footprint ""
		(layer "B.Cu")
		(at 91.47302 -75.772518)
		(property "Reference" "R164"
			(at 4.07797 0.606044 0)
			(unlocked yes)
			(layer "B.SilkS")
			(effects
				(font
					(size 0.7874 0.5842)
					(thickness 0.1524)
				)
				(justify left mirror)
			)
		)
		(property "Value" ""
			(at 0 0 0)
			(layer "B.Fab")
			(effects
				(font
					(size 1.27 1.27)
				)
				(justify mirror)
			)
		)
		(duplicate_pad_numbers_are_jumpers no)
		(fp_line
			(start -0.7874 -0.4064)
			(end -0.7874 0.4064)
			(stroke
				(width 0.1524)
				(type default)
			)
			(layer "B.SilkS")
		)
		(fp_line
			(start -0.7874 0.4064)
			(end 0.7874 0.4064)
			(stroke
				(width 0.1524)
				(type default)
			)
			(layer "B.SilkS")
		)
		(fp_line
			(start 0.7874 -0.4064)
			(end -0.7874 -0.4064)
			(stroke
				(width 0.1524)
				(type default)
			)
			(layer "B.SilkS")
		)
		(fp_line
			(start 0.7874 0.4064)
			(end 0.7874 -0.4064)
			(stroke
				(width 0.1524)
				(type default)
			)
			(layer "B.SilkS")
		)
		(fp_poly
			(pts
				(xy 0.508 0.2794) (xy 0.508 0.2286) (xy 0.635 0.2286) (xy 0.635 -0.254) (xy 0.5334 -0.254) (xy 0.5334 -0.2794)
				(xy -0.5334 -0.2794) (xy -0.5334 -0.254) (xy -0.635 -0.254) (xy -0.635 0.254) (xy -0.5334 0.254)
				(xy -0.5334 0.2794)
			)
			(stroke
				(width 0)
				(type default)
			)
			(fill no)
			(layer "B.CrtYd")
		)
		(pad "1" smd rect
			(at -0.40005 0 180)
			(size 0.4572 0.508)
			(layers "B.Cu" "B.Mask" "B.Paste")
			(net "PD_CPU_NODE1_MEM_SPEED1")
		)
		(pad "2" smd rect
			(at 0.40005 0 180)
			(size 0.4572 0.508)
			(layers "B.Cu" "B.Mask" "B.Paste")
			(net "P1V05_SUS_NODE1")
		)
	)
	(footprint ""
		(layer "B.Cu")
		(at 50.53076 -185.205624 -90)
		(property "Reference" "R837"
			(at -4.15163 -0.163068 270)
			(unlocked yes)
			(layer "B.SilkS")
			(effects
				(font
					(size 0.7874 0.5842)
					(thickness 0.1524)
				)
				(justify left mirror)
			)
		)
		(property "Value" ""
			(at 0 0 90)
			(layer "B.Fab")
			(effects
				(font
					(size 1.27 1.27)
				)
				(justify mirror)
			)
		)
		(duplicate_pad_numbers_are_jumpers no)
		(fp_line
			(start -0.7874 0.4064)
			(end 0.7874 0.4064)
			(stroke
				(width 0.1524)
				(type default)
			)
			(layer "B.SilkS")
		)
		(fp_line
			(start 0.7874 0.4064)
			(end 0.7874 -0.4064)
			(stroke
				(width 0.1524)
				(type default)
			)
			(layer "B.SilkS")
		)
		(fp_line
			(start -0.7874 -0.4064)
			(end -0.7874 0.4064)
			(stroke
				(width 0.1524)
				(type default)
			)
			(layer "B.SilkS")
		)
		(fp_line
			(start 0.7874 -0.4064)
			(end -0.7874 -0.4064)
			(stroke
				(width 0.1524)
				(type default)
			)
			(layer "B.SilkS")
		)
		(fp_poly
			(pts
				(xy 0.508 0.2794) (xy 0.508 0.2286) (xy 0.635 0.2286) (xy 0.635 -0.254) (xy 0.5334 -0.254) (xy 0.5334 -0.2794)
				(xy -0.5334 -0.2794) (xy -0.5334 -0.254) (xy -0.635 -0.254) (xy -0.635 0.254) (xy -0.5334 0.254)
				(xy -0.5334 0.2794)
			)
			(stroke
				(width 0)
				(type default)
			)
			(fill no)
			(layer "B.CrtYd")
		)
		(pad "1" smd rect
			(at -0.40005 0 90)
			(size 0.4572 0.508)
			(layers "B.Cu" "B.Mask" "B.Paste")
			(net "PSU3_DC_OK_R")
		)
		(pad "2" smd rect
			(at 0.40005 0 90)
			(size 0.4572 0.508)
			(layers "B.Cu" "B.Mask" "B.Paste")
			(net "PSU3_DC_OK_R_BUF")
		)
	)
	(footprint ""
		(layer "B.Cu")
		(at 165.19398 -151.369522 180)
		(property "Reference" "C456"
			(at 1.058164 0.191008 0)
			(unlocked yes)
			(layer "B.SilkS")
			(effects
				(font
					(size 0.7874 0.5842)
					(thickness 0.1524)
				)
				(justify left mirror)
			)
		)
		(property "Value" ""
			(at 0 0 0)
			(layer "B.Fab")
			(effects
				(font
					(size 1.27 1.27)
				)
				(justify mirror)
			)
		)
		(duplicate_pad_numbers_are_jumpers no)
		(fp_line
			(start 0.7874 0.4064)
			(end 0.7874 -0.4064)
			(stroke
				(width 0.1524)
				(type default)
			)
			(layer "B.SilkS")
		)
		(fp_line
			(start 0.7874 -0.4064)
			(end -0.7874 -0.4064)
			(stroke
				(width 0.1524)
				(type default)
			)
			(layer "B.SilkS")
		)
		(fp_line
			(start 0 0.381)
			(end 0 -0.381)
			(stroke
				(width 0.1524)
				(type default)
			)
			(layer "B.SilkS")
		)
		(fp_line
			(start -0.7874 0.4064)
			(end 0.7874 0.4064)
			(stroke
				(width 0.1524)
				(type default)
			)
			(layer "B.SilkS")
		)
		(fp_line
			(start -0.7874 -0.4064)
			(end -0.7874 0.4064)
			(stroke
				(width 0.1524)
				(type default)
			)
			(layer "B.SilkS")
		)
		(fp_poly
			(pts
				(xy 0.5334 0.254) (xy 0.635 0.254) (xy 0.635 0.2286) (xy 0.635 -0.254) (xy 0.5334 -0.254) (xy 0.5334 -0.2794)
				(xy -0.5334 -0.2794) (xy -0.5334 -0.254) (xy -0.635 -0.254) (xy -0.635 0.254) (xy -0.5334 0.254)
				(xy -0.5334 0.2794) (xy 0.508 0.2794) (xy 0.5334 0.2794)
			)
			(stroke
				(width 0)
				(type default)
			)
			(fill no)
			(layer "B.CrtYd")
		)
		(pad "1" smd rect
			(at -0.40005 0)
			(size 0.4572 0.508)
			(layers "B.Cu" "B.Mask" "B.Paste")
			(net "P1V9_LAN2")
		)
		(pad "2" smd rect
			(at 0.40005 0)
			(size 0.4572 0.508)
			(layers "B.Cu" "B.Mask" "B.Paste")
			(net "GND")
		)
	)
	(footprint ""
		(layer "B.Cu")
		(at 61.320172 -129.91211)
		(property "Reference" "C270"
			(at -40.546782 53.033676 0)
			(unlocked yes)
			(layer "B.SilkS")
			(effects
				(font
					(size 0.7874 0.5842)
					(thickness 0.1524)
				)
				(justify left mirror)
			)
		)
		(property "Value" ""
			(at 0 0 0)
			(layer "B.Fab")
			(effects
				(font
					(size 1.27 1.27)
				)
				(justify mirror)
			)
		)
		(duplicate_pad_numbers_are_jumpers no)
		(fp_line
			(start -0.7874 -0.4064)
			(end -0.7874 0.4064)
			(stroke
				(width 0.1524)
				(type default)
			)
			(layer "B.SilkS")
		)
		(fp_line
			(start -0.7874 0.4064)
			(end 0.7874 0.4064)
			(stroke
				(width 0.1524)
				(type default)
			)
			(layer "B.SilkS")
		)
		(fp_line
			(start 0 0.381)
			(end 0 -0.381)
			(stroke
				(width 0.1524)
				(type default)
			)
			(layer "B.SilkS")
		)
		(fp_line
			(start 0.7874 -0.4064)
			(end -0.7874 -0.4064)
			(stroke
				(width 0.1524)
				(type default)
			)
			(layer "B.SilkS")
		)
		(fp_line
			(start 0.7874 0.4064)
			(end 0.7874 -0.4064)
			(stroke
				(width 0.1524)
				(type default)
			)
			(layer "B.SilkS")
		)
		(fp_poly
			(pts
				(xy 0.5334 0.254) (xy 0.635 0.254) (xy 0.635 0.2286) (xy 0.635 -0.254) (xy 0.5334 -0.254) (xy 0.5334 -0.2794)
				(xy -0.5334 -0.2794) (xy -0.5334 -0.254) (xy -0.635 -0.254) (xy -0.635 0.254) (xy -0.5334 0.254)
				(xy -0.5334 0.2794) (xy 0.508 0.2794) (xy 0.5334 0.2794)
			)
			(stroke
				(width 0)
				(type default)
			)
			(fill no)
			(layer "B.CrtYd")
		)
		(pad "1" smd rect
			(at -0.40005 0 180)
			(size 0.4572 0.508)
			(layers "B.Cu" "B.Mask" "B.Paste")
			(net "BMC_NODE1_HPLLAV33")
		)
		(pad "2" smd rect
			(at 0.40005 0 180)
			(size 0.4572 0.508)
			(layers "B.Cu" "B.Mask" "B.Paste")
			(net "GND")
		)
	)
	(footprint ""
		(layer "B.Cu")
		(at 51.675538 -77.804518 -90)
		(property "Reference" "C59"
			(at 32.241744 15.405608 270)
			(unlocked yes)
			(layer "B.SilkS")
			(effects
				(font
					(size 0.7874 0.5842)
					(thickness 0.1524)
				)
				(justify left mirror)
			)
		)
		(property "Value" ""
			(at 0 0 90)
			(layer "B.Fab")
			(effects
				(font
					(size 1.27 1.27)
				)
				(justify mirror)
			)
		)
		(duplicate_pad_numbers_are_jumpers no)
		(fp_line
			(start -0.7874 0.4064)
			(end 0.7874 0.4064)
			(stroke
				(width 0.1524)
				(type default)
			)
			(layer "B.SilkS")
		)
		(fp_line
			(start 0.7874 0.4064)
			(end 0.7874 -0.4064)
			(stroke
				(width 0.1524)
				(type default)
			)
			(layer "B.SilkS")
		)
		(fp_line
			(start 0 0.381)
			(end 0 -0.381)
			(stroke
				(width 0.1524)
				(type default)
			)
			(layer "B.SilkS")
		)
		(fp_line
			(start -0.7874 -0.4064)
			(end -0.7874 0.4064)
			(stroke
				(width 0.1524)
				(type default)
			)
			(layer "B.SilkS")
		)
		(fp_line
			(start 0.7874 -0.4064)
			(end -0.7874 -0.4064)
			(stroke
				(width 0.1524)
				(type default)
			)
			(layer "B.SilkS")
		)
		(fp_poly
			(pts
				(xy 0.5334 0.254) (xy 0.635 0.254) (xy 0.635 0.2286) (xy 0.635 -0.254) (xy 0.5334 -0.254) (xy 0.5334 -0.2794)
				(xy -0.5334 -0.2794) (xy -0.5334 -0.254) (xy -0.635 -0.254) (xy -0.635 0.254) (xy -0.5334 0.254)
				(xy -0.5334 0.2794) (xy 0.508 0.2794) (xy 0.5334 0.2794)
			)
			(stroke
				(width 0)
				(type default)
			)
			(fill no)
			(layer "B.CrtYd")
		)
		(pad "1" smd rect
			(at -0.40005 0 90)
			(size 0.4572 0.508)
			(layers "B.Cu" "B.Mask" "B.Paste")
			(net "P1V05_NODE1")
		)
		(pad "2" smd rect
			(at 0.40005 0 90)
			(size 0.4572 0.508)
			(layers "B.Cu" "B.Mask" "B.Paste")
			(net "GND")
		)
	)
)
